(kicad_pcb
	(version 20240108)
	(generator "pcbnew")
	(generator_version "8.0")
	(general
		(thickness 1.62)
		(legacy_teardrops no)
	)
	(paper "A4")
	(title_block
		(title "Jetson Orin Baseboard")
		(date "2025-03-12")
		(rev "1.3.4")
		(company "Antmicro Ltd")
		(comment 1 "www.antmicro.com")
		(comment 9 "footprints 1-5 of 677")
	)
	(layers
		(0 "F.Cu" signal)
		(1 "In1.Cu" signal)
		(2 "In2.Cu" signal)
		(3 "In3.Cu" signal)
		(4 "In4.Cu" jumper)
		(5 "In5.Cu" signal)
		(6 "In6.Cu" signal)
		(31 "B.Cu" signal)
		(32 "B.Adhes" user "B.Adhesive")
		(33 "F.Adhes" user "F.Adhesive")
		(34 "B.Paste" user)
		(35 "F.Paste" user)
		(36 "B.SilkS" user "B.Silkscreen")
		(37 "F.SilkS" user "F.Silkscreen")
		(38 "B.Mask" user)
		(39 "F.Mask" user)
		(40 "Dwgs.User" user "User.Drawings")
		(41 "Cmts.User" user "User.Comments")
		(42 "Eco1.User" user "User.Eco1")
		(43 "Eco2.User" user "User.Eco2")
		(44 "Edge.Cuts" user)
		(45 "Margin" user)
		(46 "B.CrtYd" user "B.Courtyard")
		(47 "F.CrtYd" user "F.Courtyard")
		(48 "B.Fab" user)
		(49 "F.Fab" user)
	)
	(footprint "antmicro-footprints:R_0603_1608Metric"
		(layer "F.Cu")
		(at 57.3 87.5)
		(descr "Resistor SMD 0603")
		(tags "resistor SMD 0603")
		(property "Reference" "R287"
			(at -3.8 0 0)
			(layer "F.SilkS")
			(effects
				(font
					(size 0.7 0.7)
					(thickness 0.15)
				)
				(justify left bottom)
			)
		)
		(property "Value" "R_0R_22.4A_0603"
			(at 0 1.6 0)
			(layer "F.Fab")
			(effects
				(font
					(size 0.7 0.7)
					(thickness 0.15)
				)
				(justify left bottom)
			)
		)
		(property "Footprint" "antmicro-footprints:R_0603_1608Metric"
			(at 0 0 0)
			(layer "F.Fab")
			(hide yes)
			(effects
				(font
					(size 1.27 1.27)
					(thickness 0.15)
				)
			)
		)
		(property "Datasheet" "https://fscdn.rohm.com/en/products/databook/datasheet/passive/resistor/chip_resistor/pmr-jpw-e.pdf"
			(at 0 0 0)
			(layer "F.Fab")
			(hide yes)
			(effects
				(font
					(size 1.27 1.27)
					(thickness 0.15)
				)
			)
		)
		(property "Manufacturer" "ROHM Semiconductor"
			(at 0 0 0)
			(unlocked yes)
			(layer "F.Fab")
			(hide yes)
			(effects
				(font
					(size 1 1)
					(thickness 0.15)
				)
			)
		)
		(property "MPN" "PMR03EZPJ000"
			(at 0 0 0)
			(unlocked yes)
			(layer "F.Fab")
			(hide yes)
			(effects
				(font
					(size 1 1)
					(thickness 0.15)
				)
			)
		)
		(property "Val" "0R"
			(at 0 0 0)
			(unlocked yes)
			(layer "F.Fab")
			(hide yes)
			(effects
				(font
					(size 1 1)
					(thickness 0.15)
				)
			)
		)
		(property "Author" "Antmicro"
			(at 0 0 0)
			(unlocked yes)
			(layer "F.Fab")
			(hide yes)
			(effects
				(font
					(size 1 1)
					(thickness 0.15)
				)
			)
		)
		(property "License" "Apache-2.0"
			(at 0 0 0)
			(unlocked yes)
			(layer "F.Fab")
			(hide yes)
			(effects
				(font
					(size 1 1)
					(thickness 0.15)
				)
			)
		)
		(property "Max. Curr." "22.4A"
			(at 0 0 0)
			(unlocked yes)
			(layer "F.Fab")
			(hide yes)
			(effects
				(font
					(size 1 1)
					(thickness 0.15)
				)
			)
		)
		(property "Tolerance" "template_tolerance"
			(at 0 0 0)
			(unlocked yes)
			(layer "F.Fab")
			(hide yes)
			(effects
				(font
					(size 1 1)
					(thickness 0.15)
				)
			)
		)
		(sheetname "SoM")
		(sheetfile "som.kicad_sch")
		(attr smd)
		(fp_line
			(start -0.15 -0.4)
			(end 0.15 -0.4)
			(stroke
				(width 0.15)
				(type solid)
			)
			(layer "F.SilkS")
		)
		(fp_line
			(start -0.15 0.4)
			(end 0.15 0.4)
			(stroke
				(width 0.15)
				(type solid)
			)
			(layer "F.SilkS")
		)
		(fp_rect
			(start -1.25 -0.65)
			(end 1.25 0.65)
			(stroke
				(width 0.05)
				(type solid)
			)
			(fill none)
			(layer "F.CrtYd")
		)
		(fp_rect
			(start -0.8 -0.4)
			(end 0.8 0.4)
			(stroke
				(width 0.15)
				(type solid)
			)
			(fill none)
			(layer "F.Fab")
		)
		(fp_text user "Author: Antmicro"
			(at -1.25 4.9 0)
			(layer "F.Fab")
			(hide yes)
			(effects
				(font
					(size 0.7 0.7)
					(thickness 0.15)
				)
				(justify left bottom)
			)
		)
		(fp_text user "License: Apache-2.0"
			(at -1.25 5.9 0)
			(layer "F.Fab")
			(hide yes)
			(effects
				(font
					(size 0.7 0.7)
					(thickness 0.15)
				)
				(justify left bottom)
			)
		)
		(fp_text user "${REFERENCE}"
			(at -1.25 3.898 0)
			(layer "F.Fab")
			(hide yes)
			(effects
				(font
					(size 0.7 0.7)
					(thickness 0.15)
				)
				(justify left bottom)
			)
		)
		(pad "1" smd roundrect
			(at -0.7 0)
			(size 0.8 1)
			(layers "F.Cu" "F.Paste" "F.Mask")
			(roundrect_rratio 0.2)
			(net 788 "VDD_SoM")
			(pintype "passive")
		)
		(pad "2" smd roundrect
			(at 0.7 0)
			(size 0.8 1)
			(layers "F.Cu" "F.Paste" "F.Mask")
			(roundrect_rratio 0.2)
			(net 438 "/SoM/SoM_VIN")
			(pintype "passive")
		)
	)
	(footprint "antmicro-footprints:R_0402_1005Metric"
		(layer "F.Cu")
		(at 32.15 105.2 90)
		(descr "Resistor SMD 0402")
		(tags "resistor SMD 0402")
		(property "Reference" "R154"
			(at -1.4 1.3 90)
			(layer "F.SilkS")
			(effects
				(font
					(size 0.7 0.7)
					(thickness 0.15)
				)
				(justify left bottom)
			)
		)
		(property "Value" "R_24k9_0402"
			(at 0 1.4 90)
			(layer "F.Fab")
			(effects
				(font
					(size 0.7 0.7)
					(thickness 0.15)
				)
				(justify left bottom)
			)
		)
		(property "Footprint" "antmicro-footprints:R_0402_1005Metric"
			(at 0 0 90)
			(layer "F.Fab")
			(hide yes)
			(effects
				(font
					(size 1.27 1.27)
					(thickness 0.15)
				)
			)
		)
		(property "Datasheet" "https://www.bourns.com/docs/product-datasheets/cr.pdf"
			(at 0 0 90)
			(layer "F.Fab")
			(hide yes)
			(effects
				(font
					(size 1.27 1.27)
					(thickness 0.15)
				)
			)
		)
		(property "Author" "Antmicro"
			(at 137.35 73.05 0)
			(layer "F.Fab")
			(hide yes)
			(effects
				(font
					(size 1 1)
					(thickness 0.15)
				)
			)
		)
		(property "License" "Apache-2.0"
			(at 137.35 73.05 0)
			(layer "F.Fab")
			(hide yes)
			(effects
				(font
					(size 1 1)
					(thickness 0.15)
				)
			)
		)
		(property "MPN" "CR0402-FX-2492GLF"
			(at 137.35 73.05 0)
			(layer "F.Fab")
			(hide yes)
			(effects
				(font
					(size 1 1)
					(thickness 0.15)
				)
			)
		)
		(property "Manufacturer" "Bourns"
			(at 137.35 73.05 0)
			(layer "F.Fab")
			(hide yes)
			(effects
				(font
					(size 1 1)
					(thickness 0.15)
				)
			)
		)
		(property "Tolerance" "1%"
			(at 137.35 73.05 0)
			(layer "F.Fab")
			(hide yes)
			(effects
				(font
					(size 1 1)
					(thickness 0.15)
				)
			)
		)
		(property "Val" "24k9"
			(at 137.35 73.05 0)
			(layer "F.Fab")
			(hide yes)
			(effects
				(font
					(size 1 1)
					(thickness 0.15)
				)
			)
		)
		(sheetname "Ethernet")
		(sheetfile "ethernet.kicad_sch")
		(attr smd)
		(fp_rect
			(start -0.925 -0.47)
			(end 0.925 0.47)
			(stroke
				(width 0.05)
				(type default)
			)
			(fill none)
			(layer "F.CrtYd")
		)
		(fp_rect
			(start -0.5 -0.25)
			(end 0.5 0.25)
			(stroke
				(width 0.15)
				(type solid)
			)
			(fill none)
			(layer "F.Fab")
		)
		(fp_text user "${REFERENCE}"
			(at -0.95 3.168 90)
			(layer "F.Fab")
			(hide yes)
			(effects
				(font
					(size 0.7 0.7)
					(thickness 0.15)
				)
				(justify left bottom)
			)
		)
		(fp_text user "Author: Antmicro"
			(at -0.95 4.169 90)
			(layer "F.Fab")
			(hide yes)
			(effects
				(font
					(size 0.7 0.7)
					(thickness 0.15)
				)
				(justify left bottom)
			)
		)
		(fp_text user "License: Apache-2.0"
			(at -0.95 5.169 90)
			(layer "F.Fab")
			(hide yes)
			(effects
				(font
					(size 0.7 0.7)
					(thickness 0.15)
				)
				(justify left bottom)
			)
		)
		(pad "1" smd roundrect
			(at -0.48 0 90)
			(size 0.59 0.64)
			(layers "F.Cu" "F.Paste" "F.Mask")
			(roundrect_rratio 0.25)
			(net 153 "Net-(D15-A)")
			(pintype "passive")
		)
		(pad "2" smd roundrect
			(at 0.48 0 90)
			(size 0.59 0.64)
			(layers "F.Cu" "F.Paste" "F.Mask")
			(roundrect_rratio 0.25)
			(net 105 "/Ethernet/VDD")
			(pintype "passive")
		)
	)
	(footprint "antmicro-footprints:R_0402_1005Metric"
		(layer "F.Cu")
		(at 105.15 105.05)
		(descr "Resistor SMD 0402")
		(tags "resistor SMD 0402")
		(property "Reference" "R115"
			(at -3.65 0.4 0)
			(layer "F.SilkS")
			(effects
				(font
					(size 0.7 0.7)
					(thickness 0.15)
				)
				(justify left bottom)
			)
		)
		(property "Value" "R_10k_0402"
			(at 0 1.4 0)
			(layer "F.Fab")
			(effects
				(font
					(size 0.7 0.7)
					(thickness 0.15)
				)
				(justify left bottom)
			)
		)
		(property "Footprint" "antmicro-footprints:R_0402_1005Metric"
			(at 0 0 0)
			(layer "F.Fab")
			(hide yes)
			(effects
				(font
					(size 1.27 1.27)
					(thickness 0.15)
				)
			)
		)
		(property "Datasheet" "https://www.bourns.com/docs/product-datasheets/cr.pdf"
			(at 0 0 0)
			(layer "F.Fab")
			(hide yes)
			(effects
				(font
					(size 1.27 1.27)
					(thickness 0.15)
				)
			)
		)
		(property "Author" "Antmicro"
			(at 0 0 0)
			(layer "F.Fab")
			(hide yes)
			(effects
				(font
					(size 1 1)
					(thickness 0.15)
				)
			)
		)
		(property "License" "Apache-2.0"
			(at 0 0 0)
			(layer "F.Fab")
			(hide yes)
			(effects
				(font
					(size 1 1)
					(thickness 0.15)
				)
			)
		)
		(property "MPN" "CR0402-FX-1002GLF"
			(at 0 0 0)
			(layer "F.Fab")
			(hide yes)
			(effects
				(font
					(size 1 1)
					(thickness 0.15)
				)
			)
		)
		(property "Manufacturer" "Bourns"
			(at 0 0 0)
			(layer "F.Fab")
			(hide yes)
			(effects
				(font
					(size 1 1)
					(thickness 0.15)
				)
			)
		)
		(property "Tolerance" "1%"
			(at 0 0 0)
			(layer "F.Fab")
			(hide yes)
			(effects
				(font
					(size 1 1)
					(thickness 0.15)
				)
			)
		)
		(property "Val" "10k"
			(at 0 0 0)
			(layer "F.Fab")
			(hide yes)
			(effects
				(font
					(size 1 1)
					(thickness 0.15)
				)
			)
		)
		(sheetname "USB3")
		(sheetfile "usb3.kicad_sch")
		(attr smd exclude_from_pos_files exclude_from_bom dnp)
		(fp_rect
			(start -0.925 -0.47)
			(end 0.925 0.47)
			(stroke
				(width 0.05)
				(type default)
			)
			(fill none)
			(layer "F.CrtYd")
		)
		(fp_rect
			(start -0.5 -0.25)
			(end 0.5 0.25)
			(stroke
				(width 0.15)
				(type solid)
			)
			(fill none)
			(layer "F.Fab")
		)
		(fp_text user "License: Apache-2.0"
			(at -0.95 5.169 0)
			(layer "F.Fab")
			(hide yes)
			(effects
				(font
					(size 0.7 0.7)
					(thickness 0.15)
				)
				(justify left bottom)
			)
		)
		(fp_text user "Author: Antmicro"
			(at -0.95 4.169 0)
			(layer "F.Fab")
			(hide yes)
			(effects
				(font
					(size 0.7 0.7)
					(thickness 0.15)
				)
				(justify left bottom)
			)
		)
		(fp_text user "${REFERENCE}"
			(at -0.95 3.168 0)
			(layer "F.Fab")
			(hide yes)
			(effects
				(font
					(size 0.7 0.7)
					(thickness 0.15)
				)
				(justify left bottom)
			)
		)
		(pad "1" smd roundrect
			(at -0.48 0)
			(size 0.59 0.64)
			(layers "F.Cu" "F.Paste" "F.Mask")
			(roundrect_rratio 0.25)
			(net 99 "+5V")
			(pintype "passive")
		)
		(pad "2" smd roundrect
			(at 0.48 0)
			(size 0.59 0.64)
			(layers "F.Cu" "F.Paste" "F.Mask")
			(roundrect_rratio 0.25)
			(net 315 "/USB3/USBC1_PORT")
			(pintype "passive")
		)
	)
	(footprint "antmicro-footprints:R_0402_1005Metric"
		(layer "F.Cu")
		(at 81.23 89.13 -90)
		(descr "Resistor SMD 0402")
		(tags "resistor SMD 0402")
		(property "Reference" "R240"
			(at -1.75 -2.4 90)
			(layer "F.SilkS")
			(effects
				(font
					(size 0.7 0.7)
					(thickness 0.15)
				)
				(justify right bottom)
			)
		)
		(property "Value" "R_499k_0402"
			(at -1.011843 1.772047 90)
			(layer "F.Fab")
			(effects
				(font
					(size 0.7 0.7)
					(thickness 0.15)
				)
				(justify right bottom)
			)
		)
		(property "Footprint" "antmicro-footprints:R_0402_1005Metric"
			(at 0 0 -90)
			(layer "F.Fab")
			(hide yes)
			(effects
				(font
					(size 1.27 1.27)
					(thickness 0.15)
				)
			)
		)
		(property "Datasheet" "https://www.mouser.com/datasheet/2/54/cr-1858361.pdf"
			(at 0 0 -90)
			(layer "F.Fab")
			(hide yes)
			(effects
				(font
					(size 1.27 1.27)
					(thickness 0.15)
				)
			)
		)
		(property "Author" "Antmicro"
			(at -7.9 170.36 0)
			(layer "F.Fab")
			(hide yes)
			(effects
				(font
					(size 1 1)
					(thickness 0.15)
				)
			)
		)
		(property "License" "Apache-2.0"
			(at -7.9 170.36 0)
			(layer "F.Fab")
			(hide yes)
			(effects
				(font
					(size 1 1)
					(thickness 0.15)
				)
			)
		)
		(property "MPN" "CR0402-FX-4993GLF"
			(at -7.9 170.36 0)
			(layer "F.Fab")
			(hide yes)
			(effects
				(font
					(size 1 1)
					(thickness 0.15)
				)
			)
		)
		(property "Manufacturer" "Bourns"
			(at -7.9 170.36 0)
			(layer "F.Fab")
			(hide yes)
			(effects
				(font
					(size 1 1)
					(thickness 0.15)
				)
			)
		)
		(property "Tolerance" "1%"
			(at -7.9 170.36 0)
			(layer "F.Fab")
			(hide yes)
			(effects
				(font
					(size 1 1)
					(thickness 0.15)
				)
			)
		)
		(property "Val" "499k"
			(at -7.9 170.36 0)
			(layer "F.Fab")
			(hide yes)
			(effects
				(font
					(size 1 1)
					(thickness 0.15)
				)
			)
		)
		(sheetname "Supply")
		(sheetfile "supply.kicad_sch")
		(attr smd exclude_from_pos_files exclude_from_bom dnp)
		(fp_rect
			(start -0.925 -0.47)
			(end 0.925 0.47)
			(stroke
				(width 0.05)
				(type default)
			)
			(fill none)
			(layer "F.CrtYd")
		)
		(fp_rect
			(start -0.5 -0.25)
			(end 0.5 0.25)
			(stroke
				(width 0.15)
				(type solid)
			)
			(fill none)
			(layer "F.Fab")
		)
		(fp_text user "${REFERENCE}"
			(at -0.95 3.168 90)
			(layer "F.Fab")
			(hide yes)
			(effects
				(font
					(size 0.7 0.7)
					(thickness 0.15)
				)
				(justify right bottom)
			)
		)
		(fp_text user "License: Apache-2.0"
			(at -0.95 5.169 90)
			(layer "F.Fab")
			(hide yes)
			(effects
				(font
					(size 0.7 0.7)
					(thickness 0.15)
				)
				(justify right bottom)
			)
		)
		(fp_text user "Author: Antmicro"
			(at -0.95 4.169 90)
			(layer "F.Fab")
			(hide yes)
			(effects
				(font
					(size 0.7 0.7)
					(thickness 0.15)
				)
				(justify right bottom)
			)
		)
		(pad "1" smd roundrect
			(at -0.48 0 270)
			(size 0.59 0.64)
			(layers "F.Cu" "F.Paste" "F.Mask")
			(roundrect_rratio 0.25)
			(net 687 "/Supply/3V3_MODE1")
			(pintype "passive")
		)
		(pad "2" smd roundrect
			(at 0.48 0 270)
			(size 0.59 0.64)
			(layers "F.Cu" "F.Paste" "F.Mask")
			(roundrect_rratio 0.25)
			(net 177 "/Supply/3V3_VDD")
			(pintype "passive")
		)
	)
	(footprint "antmicro-footprints:C_0603_1608Metric"
		(layer "F.Cu")
		(at 102.95 122.95 180)
		(descr "Capacitor SMD 0603")
		(tags "capacitor 0603")
		(property "Reference" "C74"
			(at -1.075 -0.5 180)
			(layer "F.SilkS")
			(effects
				(font
					(size 0.7 0.7)
					(thickness 0.15)
				)
				(justify left bottom)
			)
		)
		(property "Value" "C_10u_0603"
			(at 0 1.6 180)
			(layer "F.Fab")
			(effects
				(font
					(size 0.7 0.7)
					(thickness 0.15)
				)
				(justify left bottom)
			)
		)
		(property "Footprint" "antmicro-footprints:C_0603_1608Metric"
			(at 0 0 180)
			(layer "F.Fab")
			(hide yes)
			(effects
				(font
					(size 1.27 1.27)
					(thickness 0.15)
				)
			)
		)
		(property "Datasheet" "https://www.murata.com/products/productdetail?partno=GRM188R61A106KE69%23"
			(at 0 0 180)
			(layer "F.Fab")
			(hide yes)
			(effects
				(font
					(size 1.27 1.27)
					(thickness 0.15)
				)
			)
		)
		(property "Author" "Antmicro"
			(at 205.9 245.9 0)
			(layer "F.Fab")
			(hide yes)
			(effects
				(font
					(size 1 1)
					(thickness 0.15)
				)
			)
		)
		(property "Dielectric" "template_dielectric"
			(at 205.9 245.9 0)
			(layer "F.Fab")
			(hide yes)
			(effects
				(font
					(size 1 1)
					(thickness 0.15)
				)
			)
		)
		(property "License" "Apache-2.0"
			(at 205.9 245.9 0)
			(layer "F.Fab")
			(hide yes)
			(effects
				(font
					(size 1 1)
					(thickness 0.15)
				)
			)
		)
		(property "MPN" "GRM188R61A106KE69D"
			(at 205.9 245.9 0)
			(layer "F.Fab")
			(hide yes)
			(effects
				(font
					(size 1 1)
					(thickness 0.15)
				)
			)
		)
		(property "Manufacturer" "Murata"
			(at 205.9 245.9 0)
			(layer "F.Fab")
			(hide yes)
			(effects
				(font
					(size 1 1)
					(thickness 0.15)
				)
			)
		)
		(property "Val" "10u"
			(at 205.9 245.9 0)
			(layer "F.Fab")
			(hide yes)
			(effects
				(font
					(size 1 1)
					(thickness 0.15)
				)
			)
		)
		(property "Voltage" ""
			(at 205.9 245.9 0)
			(layer "F.Fab")
			(hide yes)
			(effects
				(font
					(size 1 1)
					(thickness 0.15)
				)
			)
		)
		(sheetname "USB3")
		(sheetfile "usb3.kicad_sch")
		(attr smd)
		(fp_line
			(start -0.15 0.4)
			(end 0.15 0.4)
			(stroke
				(width 0.15)
				(type solid)
			)
			(layer "F.SilkS")
		)
		(fp_line
			(start -0.15 -0.4)
			(end 0.15 -0.4)
			(stroke
				(width 0.15)
				(type solid)
			)
			(layer "F.SilkS")
		)
		(fp_rect
			(start -1.25 -0.65)
			(end 1.25 0.65)
			(stroke
				(width 0.05)
				(type solid)
			)
			(fill none)
			(layer "F.CrtYd")
		)
		(fp_rect
			(start -0.8 -0.4)
			(end 0.8 0.4)
			(stroke
				(width 0.15)
				(type solid)
			)
			(fill none)
			(layer "F.Fab")
		)
		(fp_text user "${REFERENCE}"
			(at -1.682 3.895 180)
			(layer "F.Fab")
			(hide yes)
			(effects
				(font
					(size 0.7 0.7)
					(thickness 0.15)
				)
				(justify left bottom)
			)
		)
		(fp_text user "License: Apache-2.0"
			(at -1.682 5.895 180)
			(layer "F.Fab")
			(hide yes)
			(effects
				(font
					(size 0.7 0.7)
					(thickness 0.15)
				)
				(justify left bottom)
			)
		)
		(fp_text user "Author: Antmicro"
			(at -1.682 4.894 180)
			(layer "F.Fab")
			(hide yes)
			(effects
				(font
					(size 0.7 0.7)
					(thickness 0.15)
				)
				(justify left bottom)
			)
		)
		(pad "1" smd roundrect
			(at -0.7 0 180)
			(size 0.8 1)
			(layers "F.Cu" "F.Paste" "F.Mask")
			(roundrect_rratio 0.2)
			(net 270 "/USB3/USBC1_VBUS")
			(pintype "passive")
		)
		(pad "2" smd roundrect
			(at 0.7 0 180)
			(size 0.8 1)
			(layers "F.Cu" "F.Paste" "F.Mask")
			(roundrect_rratio 0.2)
			(net 1 "GND")
			(pintype "passive")
		)
	)
)
